FILE_TYPE = MACRO_DRAWING;
SET COLOR_WIRE YELLOW;
SET COLOR_PROP ORANGE;
SET COLOR_DOT WHITE;
SET COLOR_ARC YELLOW;
SET COLOR_BODY GREEN;
SET COLOR_NOTE PURPLE;
SET PROP_DISPLAY VALUE;
SET PAGE_NUMBER P415;
FORCEADD TAP..1
(-6750 2525);
FORCEPROP 3 LASTPIN (-6800 2525) SIG_NAME P5E_CPU0_P2_TX_C_DP<8>
J 0
(-6790 2535);
DISPLAY 0.659574 (-6790 2535);
PAINT MONO (-6790 2535);
DISPLAY INVISIBLE (-6790 2535);
FORCEPROP 1 LASTPIN (-6800 2525) BN 8
J 0
(-6812 2533);
DISPLAY 0.680851 (-6812 2533);
PAINT GREEN (-6812 2533);
FORCEPROP 2 LAST CDS_LIB standard
J 0
(-6750 2525);
DISPLAY INVISIBLE (-6750 2525);
FORCEPROP 1 LAST BODY_TYPE PLUMBING
J 0
(-6750 2575);
DISPLAY 0.872340 (-6750 2575);
PAINT GREEN (-6750 2575);
DISPLAY INVISIBLE (-6750 2575);
FORCEPROP 1 LAST HDL_TAP TRUE
J 0
(-6425 2400);
DISPLAY 0.872340 (-6425 2400);
DISPLAY INVISIBLE (-6425 2400);
FORCEPROP 1 LAST PATH I1
J 0
(-6752 2525);
DISPLAY 0.872340 (-6752 2525);
PAINT GREEN (-6752 2525);
DISPLAY INVISIBLE (-6752 2525);
FORCEADD TAP..1
(-6950 4025);
FORCEPROP 3 LASTPIN (-7000 4025) SIG_NAME P5E_CPU0_P2_TX_C_DN<12>
J 0
(-6990 4035);
DISPLAY 0.659574 (-6990 4035);
PAINT MONO (-6990 4035);
DISPLAY INVISIBLE (-6990 4035);
FORCEPROP 1 LASTPIN (-7000 4025) BN 12
J 0
(-7012 4033);
DISPLAY 0.680851 (-7012 4033);
PAINT GREEN (-7012 4033);
FORCEPROP 2 LAST CDS_LIB standard
J 0
(-6950 4025);
DISPLAY INVISIBLE (-6950 4025);
FORCEPROP 1 LAST BODY_TYPE PLUMBING
J 0
(-6950 4075);
DISPLAY 0.872340 (-6950 4075);
PAINT GREEN (-6950 4075);
DISPLAY INVISIBLE (-6950 4075);
FORCEPROP 1 LAST HDL_TAP TRUE
J 0
(-6625 3900);
DISPLAY 0.872340 (-6625 3900);
DISPLAY INVISIBLE (-6625 3900);
FORCEPROP 1 LAST PATH I10
J 0
(-6952 4025);
DISPLAY 0.872340 (-6952 4025);
PAINT GREEN (-6952 4025);
DISPLAY INVISIBLE (-6952 4025);
FORCEADD TAP..1
(-6750 4275);
FORCEPROP 3 LASTPIN (-6800 4275) SIG_NAME P5E_CPU0_P2_TX_C_DP<13>
J 0
(-6790 4285);
DISPLAY 0.659574 (-6790 4285);
PAINT MONO (-6790 4285);
DISPLAY INVISIBLE (-6790 4285);
FORCEPROP 1 LASTPIN (-6800 4275) BN 13
J 0
(-6812 4283);
DISPLAY 0.680851 (-6812 4283);
PAINT GREEN (-6812 4283);
FORCEPROP 2 LAST CDS_LIB standard
J 0
(-6750 4275);
DISPLAY INVISIBLE (-6750 4275);
FORCEPROP 1 LAST BODY_TYPE PLUMBING
J 0
(-6750 4325);
DISPLAY 0.872340 (-6750 4325);
PAINT GREEN (-6750 4325);
DISPLAY INVISIBLE (-6750 4325);
FORCEPROP 1 LAST HDL_TAP TRUE
J 0
(-6425 4150);
DISPLAY 0.872340 (-6425 4150);
DISPLAY INVISIBLE (-6425 4150);
FORCEPROP 1 LAST PATH I11
J 0
(-6752 4275);
DISPLAY 0.872340 (-6752 4275);
PAINT GREEN (-6752 4275);
DISPLAY INVISIBLE (-6752 4275);
FORCEADD TAP..1
(-6950 4375);
FORCEPROP 3 LASTPIN (-7000 4375) SIG_NAME P5E_CPU0_P2_TX_C_DN<13>
J 0
(-6990 4385);
DISPLAY 0.659574 (-6990 4385);
PAINT MONO (-6990 4385);
DISPLAY INVISIBLE (-6990 4385);
FORCEPROP 1 LASTPIN (-7000 4375) BN 13
J 0
(-7012 4383);
DISPLAY 0.680851 (-7012 4383);
PAINT GREEN (-7012 4383);
FORCEPROP 2 LAST CDS_LIB standard
J 0
(-6950 4375);
DISPLAY INVISIBLE (-6950 4375);
FORCEPROP 1 LAST BODY_TYPE PLUMBING
J 0
(-6950 4425);
DISPLAY 0.872340 (-6950 4425);
PAINT GREEN (-6950 4425);
DISPLAY INVISIBLE (-6950 4425);
FORCEPROP 1 LAST HDL_TAP TRUE
J 0
(-6625 4250);
DISPLAY 0.872340 (-6625 4250);
DISPLAY INVISIBLE (-6625 4250);
FORCEPROP 1 LAST PATH I12
J 0
(-6952 4375);
DISPLAY 0.872340 (-6952 4375);
PAINT GREEN (-6952 4375);
DISPLAY INVISIBLE (-6952 4375);
FORCEADD TAP..1
(-6750 4625);
FORCEPROP 3 LASTPIN (-6800 4625) SIG_NAME P5E_CPU0_P2_TX_C_DP<14>
J 0
(-6790 4635);
DISPLAY 0.659574 (-6790 4635);
PAINT MONO (-6790 4635);
DISPLAY INVISIBLE (-6790 4635);
FORCEPROP 1 LASTPIN (-6800 4625) BN 14
J 0
(-6812 4633);
DISPLAY 0.680851 (-6812 4633);
PAINT GREEN (-6812 4633);
FORCEPROP 2 LAST CDS_LIB standard
J 0
(-6750 4625);
DISPLAY INVISIBLE (-6750 4625);
FORCEPROP 1 LAST BODY_TYPE PLUMBING
J 0
(-6750 4675);
DISPLAY 0.872340 (-6750 4675);
PAINT GREEN (-6750 4675);
DISPLAY INVISIBLE (-6750 4675);
FORCEPROP 1 LAST HDL_TAP TRUE
J 0
(-6425 4500);
DISPLAY 0.872340 (-6425 4500);
DISPLAY INVISIBLE (-6425 4500);
FORCEPROP 1 LAST PATH I13
J 0
(-6752 4625);
DISPLAY 0.872340 (-6752 4625);
PAINT GREEN (-6752 4625);
DISPLAY INVISIBLE (-6752 4625);
FORCEADD TAP..1
(-6950 4725);
FORCEPROP 3 LASTPIN (-7000 4725) SIG_NAME P5E_CPU0_P2_TX_C_DN<14>
J 0
(-6990 4735);
DISPLAY 0.659574 (-6990 4735);
PAINT MONO (-6990 4735);
DISPLAY INVISIBLE (-6990 4735);
FORCEPROP 1 LASTPIN (-7000 4725) BN 14
J 0
(-7012 4733);
DISPLAY 0.680851 (-7012 4733);
PAINT GREEN (-7012 4733);
FORCEPROP 2 LAST CDS_LIB standard
J 0
(-6950 4725);
DISPLAY INVISIBLE (-6950 4725);
FORCEPROP 1 LAST BODY_TYPE PLUMBING
J 0
(-6950 4775);
DISPLAY 0.872340 (-6950 4775);
PAINT GREEN (-6950 4775);
DISPLAY INVISIBLE (-6950 4775);
FORCEPROP 1 LAST HDL_TAP TRUE
J 0
(-6625 4600);
DISPLAY 0.872340 (-6625 4600);
DISPLAY INVISIBLE (-6625 4600);
FORCEPROP 1 LAST PATH I14
J 0
(-6952 4725);
DISPLAY 0.872340 (-6952 4725);
PAINT GREEN (-6952 4725);
DISPLAY INVISIBLE (-6952 4725);
FORCEADD TAP..1
(-6750 4975);
FORCEPROP 3 LASTPIN (-6800 4975) SIG_NAME P5E_CPU0_P2_TX_C_DP<15>
J 0
(-6790 4985);
DISPLAY 0.659574 (-6790 4985);
PAINT MONO (-6790 4985);
DISPLAY INVISIBLE (-6790 4985);
FORCEPROP 1 LASTPIN (-6800 4975) BN 15
J 0
(-6812 4983);
DISPLAY 0.680851 (-6812 4983);
PAINT GREEN (-6812 4983);
FORCEPROP 2 LAST CDS_LIB standard
J 0
(-6750 4975);
DISPLAY INVISIBLE (-6750 4975);
FORCEPROP 1 LAST BODY_TYPE PLUMBING
J 0
(-6750 5025);
DISPLAY 0.872340 (-6750 5025);
PAINT GREEN (-6750 5025);
DISPLAY INVISIBLE (-6750 5025);
FORCEPROP 1 LAST HDL_TAP TRUE
J 0
(-6425 4850);
DISPLAY 0.872340 (-6425 4850);
DISPLAY INVISIBLE (-6425 4850);
FORCEPROP 1 LAST PATH I15
J 0
(-6752 4975);
DISPLAY 0.872340 (-6752 4975);
PAINT GREEN (-6752 4975);
DISPLAY INVISIBLE (-6752 4975);
FORCEADD TAP..1
(-6950 5075);
FORCEPROP 3 LASTPIN (-7000 5075) SIG_NAME P5E_CPU0_P2_TX_C_DN<15>
J 0
(-6990 5085);
DISPLAY 0.659574 (-6990 5085);
PAINT MONO (-6990 5085);
DISPLAY INVISIBLE (-6990 5085);
FORCEPROP 1 LASTPIN (-7000 5075) BN 15
J 0
(-7012 5083);
DISPLAY 0.680851 (-7012 5083);
PAINT GREEN (-7012 5083);
FORCEPROP 2 LAST CDS_LIB standard
J 0
(-6950 5075);
DISPLAY INVISIBLE (-6950 5075);
FORCEPROP 1 LAST BODY_TYPE PLUMBING
J 0
(-6950 5125);
DISPLAY 0.872340 (-6950 5125);
PAINT GREEN (-6950 5125);
DISPLAY INVISIBLE (-6950 5125);
FORCEPROP 1 LAST HDL_TAP TRUE
J 0
(-6625 4950);
DISPLAY 0.872340 (-6625 4950);
DISPLAY INVISIBLE (-6625 4950);
FORCEPROP 1 LAST PATH I16
J 0
(-6952 5075);
DISPLAY 0.872340 (-6952 5075);
PAINT GREEN (-6952 5075);
DISPLAY INVISIBLE (-6952 5075);
FORCEADD OFFPAGE..1
R 2
(-5750 5000);
FORCEPROP 2 LAST $XR0 64 
J 0
(-5564 5000);
DISPLAY 0.638298 (-5564 5000);
PAINT MONO (-5564 5000);
FORCEPROP 2 LAST CDS_LIB standard
J 0
(-5750 5000);
DISPLAY INVISIBLE (-5750 5000);
FORCEPROP 1 LAST OFFPAGE TRUE
J 2
(-6075 4875);
DISPLAY 0.872340 (-6075 4875);
DISPLAY INVISIBLE (-6075 4875);
FORCEPROP 1 LAST COMMENT_BODY TRUE
J 2
(-5875 4900);
DISPLAY 0.872340 (-5875 4900);
PAINT GREEN (-5875 4900);
DISPLAY INVISIBLE (-5875 4900);
FORCEPROP 2 LAST PATH I17
J 0
(-5575 5075);
DISPLAY 0.680851 (-5575 5075);
DISPLAY INVISIBLE (-5575 5075);
FORCEADD OFFPAGE..1
R 2
(-5750 5100);
FORCEPROP 2 LAST $XR0 64 
J 0
(-5564 5100);
DISPLAY 0.638298 (-5564 5100);
PAINT MONO (-5564 5100);
FORCEPROP 2 LAST CDS_LIB standard
J 2
(-5750 5100);
DISPLAY INVISIBLE (-5750 5100);
FORCEPROP 1 LAST OFFPAGE TRUE
J 2
(-6075 4975);
DISPLAY 0.872340 (-6075 4975);
DISPLAY INVISIBLE (-6075 4975);
FORCEPROP 1 LAST COMMENT_BODY TRUE
J 2
(-5875 5000);
DISPLAY 0.872340 (-5875 5000);
PAINT GREEN (-5875 5000);
DISPLAY INVISIBLE (-5875 5000);
FORCEPROP 2 LAST PATH I18
J 0
(-5575 5175);
DISPLAY 0.680851 (-5575 5175);
DISPLAY INVISIBLE (-5575 5175);
FORCEADD TAP..1
(-2125 2475);
FORCEPROP 3 LASTPIN (-2175 2475) SIG_NAME P5E_CPU0_P2_TX_C_DP<0>
J 0
(-2165 2485);
DISPLAY 0.659574 (-2165 2485);
PAINT MONO (-2165 2485);
DISPLAY INVISIBLE (-2165 2485);
FORCEPROP 1 LASTPIN (-2175 2475) BN 0
J 0
(-2187 2483);
DISPLAY 0.680851 (-2187 2483);
PAINT GREEN (-2187 2483);
FORCEPROP 2 LAST CDS_LIB standard
J 0
(-2125 2475);
DISPLAY INVISIBLE (-2125 2475);
FORCEPROP 1 LAST BODY_TYPE PLUMBING
J 0
(-2125 2525);
DISPLAY 0.872340 (-2125 2525);
PAINT GREEN (-2125 2525);
DISPLAY INVISIBLE (-2125 2525);
FORCEPROP 1 LAST HDL_TAP TRUE
J 0
(-1800 2350);
DISPLAY 0.872340 (-1800 2350);
DISPLAY INVISIBLE (-1800 2350);
FORCEPROP 1 LAST PATH I19
J 0
(-2127 2475);
DISPLAY 0.872340 (-2127 2475);
PAINT GREEN (-2127 2475);
DISPLAY INVISIBLE (-2127 2475);
FORCEADD TAP..1
(-6950 2625);
FORCEPROP 3 LASTPIN (-7000 2625) SIG_NAME P5E_CPU0_P2_TX_C_DN<8>
J 0
(-6990 2635);
DISPLAY 0.659574 (-6990 2635);
PAINT MONO (-6990 2635);
DISPLAY INVISIBLE (-6990 2635);
FORCEPROP 1 LASTPIN (-7000 2625) BN 8
J 0
(-7012 2633);
DISPLAY 0.680851 (-7012 2633);
PAINT GREEN (-7012 2633);
FORCEPROP 2 LAST CDS_LIB standard
J 0
(-6950 2625);
DISPLAY INVISIBLE (-6950 2625);
FORCEPROP 1 LAST BODY_TYPE PLUMBING
J 0
(-6950 2675);
DISPLAY 0.872340 (-6950 2675);
PAINT GREEN (-6950 2675);
DISPLAY INVISIBLE (-6950 2675);
FORCEPROP 1 LAST HDL_TAP TRUE
J 0
(-6625 2500);
DISPLAY 0.872340 (-6625 2500);
DISPLAY INVISIBLE (-6625 2500);
FORCEPROP 1 LAST PATH I2
J 0
(-6952 2625);
DISPLAY 0.872340 (-6952 2625);
PAINT GREEN (-6952 2625);
DISPLAY INVISIBLE (-6952 2625);
FORCEADD TAP..1
(-2325 2575);
FORCEPROP 3 LASTPIN (-2375 2575) SIG_NAME P5E_CPU0_P2_TX_C_DN<0>
J 0
(-2365 2585);
DISPLAY 0.659574 (-2365 2585);
PAINT MONO (-2365 2585);
DISPLAY INVISIBLE (-2365 2585);
FORCEPROP 1 LASTPIN (-2375 2575) BN 0
J 0
(-2387 2583);
DISPLAY 0.680851 (-2387 2583);
PAINT GREEN (-2387 2583);
FORCEPROP 2 LAST CDS_LIB standard
J 0
(-2325 2575);
DISPLAY INVISIBLE (-2325 2575);
FORCEPROP 1 LAST BODY_TYPE PLUMBING
J 0
(-2325 2625);
DISPLAY 0.872340 (-2325 2625);
PAINT GREEN (-2325 2625);
DISPLAY INVISIBLE (-2325 2625);
FORCEPROP 1 LAST HDL_TAP TRUE
J 0
(-2000 2450);
DISPLAY 0.872340 (-2000 2450);
DISPLAY INVISIBLE (-2000 2450);
FORCEPROP 1 LAST PATH I20
J 0
(-2327 2575);
DISPLAY 0.872340 (-2327 2575);
PAINT GREEN (-2327 2575);
DISPLAY INVISIBLE (-2327 2575);
FORCEADD TAP..1
(-2325 2825);
FORCEPROP 3 LASTPIN (-2375 2825) SIG_NAME P5E_CPU0_P2_TX_C_DN<1>
J 0
(-2365 2835);
DISPLAY 0.659574 (-2365 2835);
PAINT MONO (-2365 2835);
DISPLAY INVISIBLE (-2365 2835);
FORCEPROP 1 LASTPIN (-2375 2825) BN 1
J 0
(-2387 2833);
DISPLAY 0.680851 (-2387 2833);
PAINT GREEN (-2387 2833);
FORCEPROP 2 LAST CDS_LIB standard
J 0
(-2325 2825);
DISPLAY INVISIBLE (-2325 2825);
FORCEPROP 1 LAST BODY_TYPE PLUMBING
J 0
(-2325 2875);
DISPLAY 0.872340 (-2325 2875);
PAINT GREEN (-2325 2875);
DISPLAY INVISIBLE (-2325 2875);
FORCEPROP 1 LAST HDL_TAP TRUE
J 0
(-2000 2700);
DISPLAY 0.872340 (-2000 2700);
DISPLAY INVISIBLE (-2000 2700);
FORCEPROP 1 LAST PATH I21
J 0
(-2327 2825);
DISPLAY 0.872340 (-2327 2825);
PAINT GREEN (-2327 2825);
DISPLAY INVISIBLE (-2327 2825);
FORCEADD TAP..1
(-2125 2925);
FORCEPROP 3 LASTPIN (-2175 2925) SIG_NAME P5E_CPU0_P2_TX_C_DP<1>
J 0
(-2165 2935);
DISPLAY 0.659574 (-2165 2935);
PAINT MONO (-2165 2935);
DISPLAY INVISIBLE (-2165 2935);
FORCEPROP 1 LASTPIN (-2175 2925) BN 1
J 0
(-2187 2933);
DISPLAY 0.680851 (-2187 2933);
PAINT GREEN (-2187 2933);
FORCEPROP 2 LAST CDS_LIB standard
J 0
(-2125 2925);
DISPLAY INVISIBLE (-2125 2925);
FORCEPROP 1 LAST BODY_TYPE PLUMBING
J 0
(-2125 2975);
DISPLAY 0.872340 (-2125 2975);
PAINT GREEN (-2125 2975);
DISPLAY INVISIBLE (-2125 2975);
FORCEPROP 1 LAST HDL_TAP TRUE
J 0
(-1800 2800);
DISPLAY 0.872340 (-1800 2800);
DISPLAY INVISIBLE (-1800 2800);
FORCEPROP 1 LAST PATH I22
J 0
(-2127 2925);
DISPLAY 0.872340 (-2127 2925);
PAINT GREEN (-2127 2925);
DISPLAY INVISIBLE (-2127 2925);
FORCEADD TAP..1
(-2325 3275);
FORCEPROP 3 LASTPIN (-2375 3275) SIG_NAME P5E_CPU0_P2_TX_C_DN<2>
J 0
(-2365 3285);
DISPLAY 0.659574 (-2365 3285);
PAINT MONO (-2365 3285);
DISPLAY INVISIBLE (-2365 3285);
FORCEPROP 1 LASTPIN (-2375 3275) BN 2
J 0
(-2387 3283);
DISPLAY 0.680851 (-2387 3283);
PAINT GREEN (-2387 3283);
FORCEPROP 2 LAST CDS_LIB standard
J 0
(-2325 3275);
DISPLAY INVISIBLE (-2325 3275);
FORCEPROP 1 LAST BODY_TYPE PLUMBING
J 0
(-2325 3325);
DISPLAY 0.872340 (-2325 3325);
PAINT GREEN (-2325 3325);
DISPLAY INVISIBLE (-2325 3325);
FORCEPROP 1 LAST HDL_TAP TRUE
J 0
(-2000 3150);
DISPLAY 0.872340 (-2000 3150);
DISPLAY INVISIBLE (-2000 3150);
FORCEPROP 1 LAST PATH I23
J 0
(-2327 3275);
DISPLAY 0.872340 (-2327 3275);
PAINT GREEN (-2327 3275);
DISPLAY INVISIBLE (-2327 3275);
FORCEADD TAP..1
(-2125 3175);
FORCEPROP 3 LASTPIN (-2175 3175) SIG_NAME P5E_CPU0_P2_TX_C_DP<2>
J 0
(-2165 3185);
DISPLAY 0.659574 (-2165 3185);
PAINT MONO (-2165 3185);
DISPLAY INVISIBLE (-2165 3185);
FORCEPROP 1 LASTPIN (-2175 3175) BN 2
J 0
(-2187 3183);
DISPLAY 0.680851 (-2187 3183);
PAINT GREEN (-2187 3183);
FORCEPROP 2 LAST CDS_LIB standard
J 0
(-2125 3175);
DISPLAY INVISIBLE (-2125 3175);
FORCEPROP 1 LAST BODY_TYPE PLUMBING
J 0
(-2125 3225);
DISPLAY 0.872340 (-2125 3225);
PAINT GREEN (-2125 3225);
DISPLAY INVISIBLE (-2125 3225);
FORCEPROP 1 LAST HDL_TAP TRUE
J 0
(-1800 3050);
DISPLAY 0.872340 (-1800 3050);
DISPLAY INVISIBLE (-1800 3050);
FORCEPROP 1 LAST PATH I24
J 0
(-2127 3175);
DISPLAY 0.872340 (-2127 3175);
PAINT GREEN (-2127 3175);
DISPLAY INVISIBLE (-2127 3175);
FORCEADD TAP..1
(-2325 3625);
FORCEPROP 3 LASTPIN (-2375 3625) SIG_NAME P5E_CPU0_P2_TX_C_DN<3>
J 0
(-2365 3635);
DISPLAY 0.659574 (-2365 3635);
PAINT MONO (-2365 3635);
DISPLAY INVISIBLE (-2365 3635);
FORCEPROP 1 LASTPIN (-2375 3625) BN 3
J 0
(-2387 3633);
DISPLAY 0.680851 (-2387 3633);
PAINT GREEN (-2387 3633);
FORCEPROP 2 LAST CDS_LIB standard
J 0
(-2325 3625);
DISPLAY INVISIBLE (-2325 3625);
FORCEPROP 1 LAST BODY_TYPE PLUMBING
J 0
(-2325 3675);
DISPLAY 0.872340 (-2325 3675);
PAINT GREEN (-2325 3675);
DISPLAY INVISIBLE (-2325 3675);
FORCEPROP 1 LAST HDL_TAP TRUE
J 0
(-2000 3500);
DISPLAY 0.872340 (-2000 3500);
DISPLAY INVISIBLE (-2000 3500);
FORCEPROP 1 LAST PATH I25
J 0
(-2327 3625);
DISPLAY 0.872340 (-2327 3625);
PAINT GREEN (-2327 3625);
DISPLAY INVISIBLE (-2327 3625);
FORCEADD TAP..1
(-2125 3525);
FORCEPROP 3 LASTPIN (-2175 3525) SIG_NAME P5E_CPU0_P2_TX_C_DP<3>
J 0
(-2165 3535);
DISPLAY 0.659574 (-2165 3535);
PAINT MONO (-2165 3535);
DISPLAY INVISIBLE (-2165 3535);
FORCEPROP 1 LASTPIN (-2175 3525) BN 3
J 0
(-2187 3533);
DISPLAY 0.680851 (-2187 3533);
PAINT GREEN (-2187 3533);
FORCEPROP 2 LAST CDS_LIB standard
J 0
(-2125 3525);
DISPLAY INVISIBLE (-2125 3525);
FORCEPROP 1 LAST BODY_TYPE PLUMBING
J 0
(-2125 3575);
DISPLAY 0.872340 (-2125 3575);
PAINT GREEN (-2125 3575);
DISPLAY INVISIBLE (-2125 3575);
FORCEPROP 1 LAST HDL_TAP TRUE
J 0
(-1800 3400);
DISPLAY 0.872340 (-1800 3400);
DISPLAY INVISIBLE (-1800 3400);
FORCEPROP 1 LAST PATH I26
J 0
(-2127 3525);
DISPLAY 0.872340 (-2127 3525);
PAINT GREEN (-2127 3525);
DISPLAY INVISIBLE (-2127 3525);
FORCEADD TAP..1
(-2325 3975);
FORCEPROP 3 LASTPIN (-2375 3975) SIG_NAME P5E_CPU0_P2_TX_C_DN<4>
J 0
(-2365 3985);
DISPLAY 0.659574 (-2365 3985);
PAINT MONO (-2365 3985);
DISPLAY INVISIBLE (-2365 3985);
FORCEPROP 1 LASTPIN (-2375 3975) BN 4
J 0
(-2387 3983);
DISPLAY 0.680851 (-2387 3983);
PAINT GREEN (-2387 3983);
FORCEPROP 2 LAST CDS_LIB standard
J 0
(-2325 3975);
DISPLAY INVISIBLE (-2325 3975);
FORCEPROP 1 LAST BODY_TYPE PLUMBING
J 0
(-2325 4025);
DISPLAY 0.872340 (-2325 4025);
PAINT GREEN (-2325 4025);
DISPLAY INVISIBLE (-2325 4025);
FORCEPROP 1 LAST HDL_TAP TRUE
J 0
(-2000 3850);
DISPLAY 0.872340 (-2000 3850);
DISPLAY INVISIBLE (-2000 3850);
FORCEPROP 1 LAST PATH I27
J 0
(-2327 3975);
DISPLAY 0.872340 (-2327 3975);
PAINT GREEN (-2327 3975);
DISPLAY INVISIBLE (-2327 3975);
FORCEADD TAP..1
(-2125 3875);
FORCEPROP 3 LASTPIN (-2175 3875) SIG_NAME P5E_CPU0_P2_TX_C_DP<4>
J 0
(-2165 3885);
DISPLAY 0.659574 (-2165 3885);
PAINT MONO (-2165 3885);
DISPLAY INVISIBLE (-2165 3885);
FORCEPROP 1 LASTPIN (-2175 3875) BN 4
J 0
(-2187 3883);
DISPLAY 0.680851 (-2187 3883);
PAINT GREEN (-2187 3883);
FORCEPROP 2 LAST CDS_LIB standard
J 0
(-2125 3875);
DISPLAY INVISIBLE (-2125 3875);
FORCEPROP 1 LAST BODY_TYPE PLUMBING
J 0
(-2125 3925);
DISPLAY 0.872340 (-2125 3925);
PAINT GREEN (-2125 3925);
DISPLAY INVISIBLE (-2125 3925);
FORCEPROP 1 LAST HDL_TAP TRUE
J 0
(-1800 3750);
DISPLAY 0.872340 (-1800 3750);
DISPLAY INVISIBLE (-1800 3750);
FORCEPROP 1 LAST PATH I28
J 0
(-2127 3875);
DISPLAY 0.872340 (-2127 3875);
PAINT GREEN (-2127 3875);
DISPLAY INVISIBLE (-2127 3875);
FORCEADD TAP..1
(-2125 4225);
FORCEPROP 3 LASTPIN (-2175 4225) SIG_NAME P5E_CPU0_P2_TX_C_DP<5>
J 0
(-2165 4235);
DISPLAY 0.659574 (-2165 4235);
PAINT MONO (-2165 4235);
DISPLAY INVISIBLE (-2165 4235);
FORCEPROP 1 LASTPIN (-2175 4225) BN 5
J 0
(-2187 4233);
DISPLAY 0.680851 (-2187 4233);
PAINT GREEN (-2187 4233);
FORCEPROP 2 LAST CDS_LIB standard
J 0
(-2125 4225);
DISPLAY INVISIBLE (-2125 4225);
FORCEPROP 1 LAST BODY_TYPE PLUMBING
J 0
(-2125 4275);
DISPLAY 0.872340 (-2125 4275);
PAINT GREEN (-2125 4275);
DISPLAY INVISIBLE (-2125 4275);
FORCEPROP 1 LAST HDL_TAP TRUE
J 0
(-1800 4100);
DISPLAY 0.872340 (-1800 4100);
DISPLAY INVISIBLE (-1800 4100);
FORCEPROP 1 LAST PATH I29
J 0
(-2127 4225);
DISPLAY 0.872340 (-2127 4225);
PAINT GREEN (-2127 4225);
DISPLAY INVISIBLE (-2127 4225);
FORCEADD TAP..1
(-6750 2875);
FORCEPROP 3 LASTPIN (-6800 2875) SIG_NAME P5E_CPU0_P2_TX_C_DP<9>
J 0
(-6790 2885);
DISPLAY 0.659574 (-6790 2885);
PAINT MONO (-6790 2885);
DISPLAY INVISIBLE (-6790 2885);
FORCEPROP 1 LASTPIN (-6800 2875) BN 9
J 0
(-6812 2883);
DISPLAY 0.680851 (-6812 2883);
PAINT GREEN (-6812 2883);
FORCEPROP 2 LAST CDS_LIB standard
J 0
(-6750 2875);
DISPLAY INVISIBLE (-6750 2875);
FORCEPROP 1 LAST BODY_TYPE PLUMBING
J 0
(-6750 2925);
DISPLAY 0.872340 (-6750 2925);
PAINT GREEN (-6750 2925);
DISPLAY INVISIBLE (-6750 2925);
FORCEPROP 1 LAST HDL_TAP TRUE
J 0
(-6425 2750);
DISPLAY 0.872340 (-6425 2750);
DISPLAY INVISIBLE (-6425 2750);
FORCEPROP 1 LAST PATH I3
J 0
(-6752 2875);
DISPLAY 0.872340 (-6752 2875);
PAINT GREEN (-6752 2875);
DISPLAY INVISIBLE (-6752 2875);
FORCEADD TAP..1
(-2325 4325);
FORCEPROP 3 LASTPIN (-2375 4325) SIG_NAME P5E_CPU0_P2_TX_C_DN<5>
J 0
(-2365 4335);
DISPLAY 0.659574 (-2365 4335);
PAINT MONO (-2365 4335);
DISPLAY INVISIBLE (-2365 4335);
FORCEPROP 1 LASTPIN (-2375 4325) BN 5
J 0
(-2387 4333);
DISPLAY 0.680851 (-2387 4333);
PAINT GREEN (-2387 4333);
FORCEPROP 2 LAST CDS_LIB standard
J 0
(-2325 4325);
DISPLAY INVISIBLE (-2325 4325);
FORCEPROP 1 LAST BODY_TYPE PLUMBING
J 0
(-2325 4375);
DISPLAY 0.872340 (-2325 4375);
PAINT GREEN (-2325 4375);
DISPLAY INVISIBLE (-2325 4375);
FORCEPROP 1 LAST HDL_TAP TRUE
J 0
(-2000 4200);
DISPLAY 0.872340 (-2000 4200);
DISPLAY INVISIBLE (-2000 4200);
FORCEPROP 1 LAST PATH I30
J 0
(-2327 4325);
DISPLAY 0.872340 (-2327 4325);
PAINT GREEN (-2327 4325);
DISPLAY INVISIBLE (-2327 4325);
FORCEADD TAP..1
(-2325 4675);
FORCEPROP 3 LASTPIN (-2375 4675) SIG_NAME P5E_CPU0_P2_TX_C_DN<6>
J 0
(-2365 4685);
DISPLAY 0.659574 (-2365 4685);
PAINT MONO (-2365 4685);
DISPLAY INVISIBLE (-2365 4685);
FORCEPROP 1 LASTPIN (-2375 4675) BN 6
J 0
(-2387 4683);
DISPLAY 0.680851 (-2387 4683);
PAINT GREEN (-2387 4683);
FORCEPROP 2 LAST CDS_LIB standard
J 0
(-2325 4675);
DISPLAY INVISIBLE (-2325 4675);
FORCEPROP 1 LAST BODY_TYPE PLUMBING
J 0
(-2325 4725);
DISPLAY 0.872340 (-2325 4725);
PAINT GREEN (-2325 4725);
DISPLAY INVISIBLE (-2325 4725);
FORCEPROP 1 LAST HDL_TAP TRUE
J 0
(-2000 4550);
DISPLAY 0.872340 (-2000 4550);
DISPLAY INVISIBLE (-2000 4550);
FORCEPROP 1 LAST PATH I31
J 0
(-2327 4675);
DISPLAY 0.872340 (-2327 4675);
PAINT GREEN (-2327 4675);
DISPLAY INVISIBLE (-2327 4675);
FORCEADD TAP..1
(-2125 4575);
FORCEPROP 3 LASTPIN (-2175 4575) SIG_NAME P5E_CPU0_P2_TX_C_DP<6>
J 0
(-2165 4585);
DISPLAY 0.659574 (-2165 4585);
PAINT MONO (-2165 4585);
DISPLAY INVISIBLE (-2165 4585);
FORCEPROP 1 LASTPIN (-2175 4575) BN 6
J 0
(-2187 4583);
DISPLAY 0.680851 (-2187 4583);
PAINT GREEN (-2187 4583);
FORCEPROP 2 LAST CDS_LIB standard
J 0
(-2125 4575);
DISPLAY INVISIBLE (-2125 4575);
FORCEPROP 1 LAST BODY_TYPE PLUMBING
J 0
(-2125 4625);
DISPLAY 0.872340 (-2125 4625);
PAINT GREEN (-2125 4625);
DISPLAY INVISIBLE (-2125 4625);
FORCEPROP 1 LAST HDL_TAP TRUE
J 0
(-1800 4450);
DISPLAY 0.872340 (-1800 4450);
DISPLAY INVISIBLE (-1800 4450);
FORCEPROP 1 LAST PATH I32
J 0
(-2127 4575);
DISPLAY 0.872340 (-2127 4575);
PAINT GREEN (-2127 4575);
DISPLAY INVISIBLE (-2127 4575);
FORCEADD TAP..1
(-2325 5025);
FORCEPROP 3 LASTPIN (-2375 5025) SIG_NAME P5E_CPU0_P2_TX_C_DN<7>
J 0
(-2365 5035);
DISPLAY 0.659574 (-2365 5035);
PAINT MONO (-2365 5035);
DISPLAY INVISIBLE (-2365 5035);
FORCEPROP 1 LASTPIN (-2375 5025) BN 7
J 0
(-2387 5033);
DISPLAY 0.680851 (-2387 5033);
PAINT GREEN (-2387 5033);
FORCEPROP 2 LAST CDS_LIB standard
J 0
(-2325 5025);
DISPLAY INVISIBLE (-2325 5025);
FORCEPROP 1 LAST BODY_TYPE PLUMBING
J 0
(-2325 5075);
DISPLAY 0.872340 (-2325 5075);
PAINT GREEN (-2325 5075);
DISPLAY INVISIBLE (-2325 5075);
FORCEPROP 1 LAST HDL_TAP TRUE
J 0
(-2000 4900);
DISPLAY 0.872340 (-2000 4900);
DISPLAY INVISIBLE (-2000 4900);
FORCEPROP 1 LAST PATH I33
J 0
(-2327 5025);
DISPLAY 0.872340 (-2327 5025);
PAINT GREEN (-2327 5025);
DISPLAY INVISIBLE (-2327 5025);
FORCEADD TAP..1
(-2125 4925);
FORCEPROP 3 LASTPIN (-2175 4925) SIG_NAME P5E_CPU0_P2_TX_C_DP<7>
J 0
(-2165 4935);
DISPLAY 0.659574 (-2165 4935);
PAINT MONO (-2165 4935);
DISPLAY INVISIBLE (-2165 4935);
FORCEPROP 1 LASTPIN (-2175 4925) BN 7
J 0
(-2187 4933);
DISPLAY 0.680851 (-2187 4933);
PAINT GREEN (-2187 4933);
FORCEPROP 2 LAST CDS_LIB standard
J 0
(-2125 4925);
DISPLAY INVISIBLE (-2125 4925);
FORCEPROP 1 LAST BODY_TYPE PLUMBING
J 0
(-2125 4975);
DISPLAY 0.872340 (-2125 4975);
PAINT GREEN (-2125 4975);
DISPLAY INVISIBLE (-2125 4975);
FORCEPROP 1 LAST HDL_TAP TRUE
J 0
(-1800 4800);
DISPLAY 0.872340 (-1800 4800);
DISPLAY INVISIBLE (-1800 4800);
FORCEPROP 1 LAST PATH I34
J 0
(-2127 4925);
DISPLAY 0.872340 (-2127 4925);
PAINT GREEN (-2127 4925);
DISPLAY INVISIBLE (-2127 4925);
FORCEADD OFFPAGE..1
R 2
(-1125 4950);
FORCEPROP 2 LAST $XR0 64 
J 0
(-939 4950);
DISPLAY 0.638298 (-939 4950);
PAINT MONO (-939 4950);
FORCEPROP 2 LAST CDS_LIB standard
J 0
(-1125 4950);
DISPLAY INVISIBLE (-1125 4950);
FORCEPROP 1 LAST OFFPAGE TRUE
J 2
(-1450 4825);
DISPLAY 0.872340 (-1450 4825);
DISPLAY INVISIBLE (-1450 4825);
FORCEPROP 1 LAST COMMENT_BODY TRUE
J 2
(-1250 4850);
DISPLAY 0.872340 (-1250 4850);
PAINT GREEN (-1250 4850);
DISPLAY INVISIBLE (-1250 4850);
FORCEPROP 2 LAST PATH I35
J 0
(-950 5025);
DISPLAY 0.680851 (-950 5025);
DISPLAY INVISIBLE (-950 5025);
FORCEADD OFFPAGE..1
R 2
(-1125 5050);
FORCEPROP 2 LAST $XR0 64 
J 0
(-939 5050);
DISPLAY 0.638298 (-939 5050);
PAINT MONO (-939 5050);
FORCEPROP 2 LAST CDS_LIB standard
J 2
(-1125 5050);
DISPLAY INVISIBLE (-1125 5050);
FORCEPROP 1 LAST OFFPAGE TRUE
J 2
(-1450 4925);
DISPLAY 0.872340 (-1450 4925);
DISPLAY INVISIBLE (-1450 4925);
FORCEPROP 1 LAST COMMENT_BODY TRUE
J 2
(-1250 4950);
DISPLAY 0.872340 (-1250 4950);
PAINT GREEN (-1250 4950);
DISPLAY INVISIBLE (-1250 4950);
FORCEPROP 2 LAST PATH I36
J 0
(-950 5125);
DISPLAY 0.680851 (-950 5125);
DISPLAY INVISIBLE (-950 5125);
FORCEADD PT5161LRS..9
(-3350 3775);
FORCEPROP 1 LAST LOCATION U6012
J 0
(-3700 5400);
DISPLAY 0.723404 (-3700 5400);
PAINT GREEN (-3700 5400);
FORCEPROP 0 LAST $SEC 9
J 0
(-3700 5550);
DISPLAY 0.680851 (-3700 5550);
PAINT MONO (-3700 5550);
DISPLAY INVISIBLE (-3700 5550);
FORCEPROP 0 LAST CDS_SEC 9
J 0
(-3700 5550);
DISPLAY 0.680851 (-3700 5550);
DISPLAY INVISIBLE (-3700 5550);
FORCEPROP 0 LASTPIN (-2900 4925) $PN CL35
J 0
(-2890 4935);
DISPLAY 0.680851 (-2890 4935);
PAINT MONO (-2890 4935);
FORCEPROP 0 LASTPIN (-2900 4575) $PN CV35
J 0
(-2890 4585);
DISPLAY 0.680851 (-2890 4585);
PAINT MONO (-2890 4585);
FORCEPROP 0 LASTPIN (-2900 4225) $PN DE35
J 0
(-2890 4235);
DISPLAY 0.680851 (-2890 4235);
PAINT MONO (-2890 4235);
FORCEPROP 0 LASTPIN (-2900 3875) $PN DM35
J 0
(-2890 3885);
DISPLAY 0.680851 (-2890 3885);
PAINT MONO (-2890 3885);
FORCEPROP 0 LASTPIN (-2900 3525) $PN DW35
J 0
(-2890 3535);
DISPLAY 0.680851 (-2890 3535);
PAINT MONO (-2890 3535);
FORCEPROP 0 LASTPIN (-2900 3175) $PN EF35
J 0
(-2890 3185);
DISPLAY 0.680851 (-2890 3185);
PAINT MONO (-2890 3185);
FORCEPROP 0 LASTPIN (-2900 2825) $PN EN35
J 0
(-2890 2835);
DISPLAY 0.680851 (-2890 2835);
PAINT MONO (-2890 2835);
FORCEPROP 0 LASTPIN (-2900 2475) $PN EY35
J 0
(-2890 2485);
DISPLAY 0.680851 (-2890 2485);
PAINT MONO (-2890 2485);
FORCEPROP 0 LASTPIN (-2900 5025) $PN CJ34
J 0
(-2890 5035);
DISPLAY 0.680851 (-2890 5035);
PAINT MONO (-2890 5035);
FORCEPROP 0 LASTPIN (-2900 4675) $PN CT34
J 0
(-2890 4685);
DISPLAY 0.680851 (-2890 4685);
PAINT MONO (-2890 4685);
FORCEPROP 0 LASTPIN (-2900 4325) $PN DC34
J 0
(-2890 4335);
DISPLAY 0.680851 (-2890 4335);
PAINT MONO (-2890 4335);
FORCEPROP 0 LASTPIN (-2900 3975) $PN DK34
J 0
(-2890 3985);
DISPLAY 0.680851 (-2890 3985);
PAINT MONO (-2890 3985);
FORCEPROP 0 LASTPIN (-2900 3625) $PN DU34
J 0
(-2890 3635);
DISPLAY 0.680851 (-2890 3635);
PAINT MONO (-2890 3635);
FORCEPROP 0 LASTPIN (-2900 3275) $PN ED34
J 0
(-2890 3285);
DISPLAY 0.680851 (-2890 3285);
PAINT MONO (-2890 3285);
FORCEPROP 0 LASTPIN (-2900 2925) $PN EL34
J 0
(-2890 2935);
DISPLAY 0.680851 (-2890 2935);
PAINT MONO (-2890 2935);
FORCEPROP 0 LASTPIN (-2900 2575) $PN EV34
J 0
(-2890 2585);
DISPLAY 0.680851 (-2890 2585);
PAINT MONO (-2890 2585);
FORCEPROP 1 LAST MATERIAL IC
J 0
(-3700 5250);
DISPLAY 0.723404 (-3700 5250);
PAINT GREEN (-3700 5250);
FORCEPROP 2 LAST PART_TYPE SMLF
J 0
(-3700 5500);
DISPLAY 0.680851 (-3700 5500);
FORCEPROP 2 LAST VALUE PT5161LRS
J 0
(-3700 5450);
DISPLAY 0.680851 (-3700 5450);
FORCEPROP 1 LAST NEEDS_NO_SIZE TRUE
J 0
(-3350 3775);
DISPLAY 0.723404 (-3350 3775);
PAINT GREEN (-3350 3775);
DISPLAY INVISIBLE (-3350 3775);
FORCEPROP 1 LAST CDS_LMAN_SYM_OUTLINE -350,1450,300,-1400
J 0
(-3350 3775);
DISPLAY 0.468085 (-3350 3775);
PAINT GREEN (-3350 3775);
DISPLAY INVISIBLE (-3350 3775);
FORCEPROP 2 LAST CDS_LIB pure_quanta
J 0
(-3350 3775);
DISPLAY INVISIBLE (-3350 3775);
FORCEPROP 1 LAST PATH I37
J 0
(-3350 3775);
DISPLAY 0.723404 (-3350 3775);
PAINT GREEN (-3350 3775);
DISPLAY INVISIBLE (-3350 3775);
FORCEPROP 1 LAST PART_NUMBER AJ051610U03
J 0
(-3700 5325);
DISPLAY 0.723404 (-3700 5325);
PAINT GREEN (-3700 5325);
DISPLAY INVISIBLE (-3700 5325);
FORCEADD PT5161LRS..8
(-7975 3825);
FORCEPROP 1 LAST LOCATION U6012
J 0
(-8325 5450);
DISPLAY 0.723404 (-8325 5450);
PAINT GREEN (-8325 5450);
FORCEPROP 0 LAST $SEC 8
J 0
(-8325 5600);
DISPLAY 0.680851 (-8325 5600);
PAINT MONO (-8325 5600);
DISPLAY INVISIBLE (-8325 5600);
FORCEPROP 0 LAST CDS_SEC 8
J 0
(-8325 5600);
DISPLAY 0.680851 (-8325 5600);
DISPLAY INVISIBLE (-8325 5600);
FORCEPROP 0 LASTPIN (-7525 4975) $PN R35
J 0
(-7515 4985);
DISPLAY 0.680851 (-7515 4985);
PAINT MONO (-7515 4985);
FORCEPROP 0 LASTPIN (-7525 4625) $PN AB35
J 0
(-7515 4635);
DISPLAY 0.680851 (-7515 4635);
PAINT MONO (-7515 4635);
FORCEPROP 0 LASTPIN (-7525 4275) $PN AJ35
J 0
(-7515 4285);
DISPLAY 0.680851 (-7515 4285);
PAINT MONO (-7515 4285);
FORCEPROP 0 LASTPIN (-7525 3925) $PN AT35
J 0
(-7515 3935);
DISPLAY 0.680851 (-7515 3935);
PAINT MONO (-7515 3935);
FORCEPROP 0 LASTPIN (-7525 3575) $PN BC35
J 0
(-7515 3585);
DISPLAY 0.680851 (-7515 3585);
PAINT MONO (-7515 3585);
FORCEPROP 0 LASTPIN (-7525 3225) $PN BK35
J 0
(-7515 3235);
DISPLAY 0.680851 (-7515 3235);
PAINT MONO (-7515 3235);
FORCEPROP 0 LASTPIN (-7525 2875) $PN BU35
J 0
(-7515 2885);
DISPLAY 0.680851 (-7515 2885);
PAINT MONO (-7515 2885);
FORCEPROP 0 LASTPIN (-7525 2525) $PN CD35
J 0
(-7515 2535);
DISPLAY 0.680851 (-7515 2535);
PAINT MONO (-7515 2535);
FORCEPROP 0 LASTPIN (-7525 5075) $PN N34
J 0
(-7515 5085);
DISPLAY 0.680851 (-7515 5085);
PAINT MONO (-7515 5085);
FORCEPROP 0 LASTPIN (-7525 4725) $PN Y34
J 0
(-7515 4735);
DISPLAY 0.680851 (-7515 4735);
PAINT MONO (-7515 4735);
FORCEPROP 0 LASTPIN (-7525 4375) $PN AG34
J 0
(-7515 4385);
DISPLAY 0.680851 (-7515 4385);
PAINT MONO (-7515 4385);
FORCEPROP 0 LASTPIN (-7525 4025) $PN AP34
J 0
(-7515 4035);
DISPLAY 0.680851 (-7515 4035);
PAINT MONO (-7515 4035);
FORCEPROP 0 LASTPIN (-7525 3675) $PN BA34
J 0
(-7515 3685);
DISPLAY 0.680851 (-7515 3685);
PAINT MONO (-7515 3685);
FORCEPROP 0 LASTPIN (-7525 3325) $PN BH34
J 0
(-7515 3335);
DISPLAY 0.680851 (-7515 3335);
PAINT MONO (-7515 3335);
FORCEPROP 0 LASTPIN (-7525 2975) $PN BR34
J 0
(-7515 2985);
DISPLAY 0.680851 (-7515 2985);
PAINT MONO (-7515 2985);
FORCEPROP 0 LASTPIN (-7525 2625) $PN CB34
J 0
(-7515 2635);
DISPLAY 0.680851 (-7515 2635);
PAINT MONO (-7515 2635);
FORCEPROP 2 LAST PART_TYPE SMLF
J 0
(-8325 5550);
DISPLAY 0.680851 (-8325 5550);
FORCEPROP 2 LAST VALUE PT5161LRS
J 0
(-8325 5500);
DISPLAY 0.680851 (-8325 5500);
FORCEPROP 1 LAST MATERIAL IC
J 0
(-8325 5300);
DISPLAY 0.723404 (-8325 5300);
PAINT GREEN (-8325 5300);
FORCEPROP 2 LAST CDS_LIB pure_quanta
J 0
(-7975 3825);
DISPLAY INVISIBLE (-7975 3825);
FORCEPROP 1 LAST CDS_LMAN_SYM_OUTLINE -350,1450,300,-1400
J 0
(-7975 3825);
DISPLAY 0.468085 (-7975 3825);
PAINT GREEN (-7975 3825);
DISPLAY INVISIBLE (-7975 3825);
FORCEPROP 1 LAST NEEDS_NO_SIZE TRUE
J 0
(-7975 3825);
DISPLAY 0.723404 (-7975 3825);
PAINT GREEN (-7975 3825);
DISPLAY INVISIBLE (-7975 3825);
FORCEPROP 1 LAST PATH I38
J 0
(-7975 3825);
DISPLAY 0.723404 (-7975 3825);
PAINT GREEN (-7975 3825);
DISPLAY INVISIBLE (-7975 3825);
FORCEPROP 1 LAST PART_NUMBER AJ051610U03
J 0
(-8325 5375);
DISPLAY 0.723404 (-8325 5375);
PAINT GREEN (-8325 5375);
DISPLAY INVISIBLE (-8325 5375);
FORCEADD TAP..1
(-6950 2975);
FORCEPROP 3 LASTPIN (-7000 2975) SIG_NAME P5E_CPU0_P2_TX_C_DN<9>
J 0
(-6990 2985);
DISPLAY 0.659574 (-6990 2985);
PAINT MONO (-6990 2985);
DISPLAY INVISIBLE (-6990 2985);
FORCEPROP 1 LASTPIN (-7000 2975) BN 9
J 0
(-7012 2983);
DISPLAY 0.680851 (-7012 2983);
PAINT GREEN (-7012 2983);
FORCEPROP 2 LAST CDS_LIB standard
J 0
(-6950 2975);
DISPLAY INVISIBLE (-6950 2975);
FORCEPROP 1 LAST BODY_TYPE PLUMBING
J 0
(-6950 3025);
DISPLAY 0.872340 (-6950 3025);
PAINT GREEN (-6950 3025);
DISPLAY INVISIBLE (-6950 3025);
FORCEPROP 1 LAST HDL_TAP TRUE
J 0
(-6625 2850);
DISPLAY 0.872340 (-6625 2850);
DISPLAY INVISIBLE (-6625 2850);
FORCEPROP 1 LAST PATH I4
J 0
(-6952 2975);
DISPLAY 0.872340 (-6952 2975);
PAINT GREEN (-6952 2975);
DISPLAY INVISIBLE (-6952 2975);
FORCEADD TAP..1
(-6750 3225);
FORCEPROP 3 LASTPIN (-6800 3225) SIG_NAME P5E_CPU0_P2_TX_C_DP<10>
J 0
(-6790 3235);
DISPLAY 0.659574 (-6790 3235);
PAINT MONO (-6790 3235);
DISPLAY INVISIBLE (-6790 3235);
FORCEPROP 1 LASTPIN (-6800 3225) BN 10
J 0
(-6812 3233);
DISPLAY 0.680851 (-6812 3233);
PAINT GREEN (-6812 3233);
FORCEPROP 2 LAST CDS_LIB standard
J 0
(-6750 3225);
DISPLAY INVISIBLE (-6750 3225);
FORCEPROP 1 LAST BODY_TYPE PLUMBING
J 0
(-6750 3275);
DISPLAY 0.872340 (-6750 3275);
PAINT GREEN (-6750 3275);
DISPLAY INVISIBLE (-6750 3275);
FORCEPROP 1 LAST HDL_TAP TRUE
J 0
(-6425 3100);
DISPLAY 0.872340 (-6425 3100);
DISPLAY INVISIBLE (-6425 3100);
FORCEPROP 1 LAST PATH I5
J 0
(-6752 3225);
DISPLAY 0.872340 (-6752 3225);
PAINT GREEN (-6752 3225);
DISPLAY INVISIBLE (-6752 3225);
FORCEADD TAP..1
(-6950 3325);
FORCEPROP 3 LASTPIN (-7000 3325) SIG_NAME P5E_CPU0_P2_TX_C_DN<10>
J 0
(-6990 3335);
DISPLAY 0.659574 (-6990 3335);
PAINT MONO (-6990 3335);
DISPLAY INVISIBLE (-6990 3335);
FORCEPROP 1 LASTPIN (-7000 3325) BN 10
J 0
(-7012 3333);
DISPLAY 0.680851 (-7012 3333);
PAINT GREEN (-7012 3333);
FORCEPROP 2 LAST CDS_LIB standard
J 0
(-6950 3325);
DISPLAY INVISIBLE (-6950 3325);
FORCEPROP 1 LAST BODY_TYPE PLUMBING
J 0
(-6950 3375);
DISPLAY 0.872340 (-6950 3375);
PAINT GREEN (-6950 3375);
DISPLAY INVISIBLE (-6950 3375);
FORCEPROP 1 LAST HDL_TAP TRUE
J 0
(-6625 3200);
DISPLAY 0.872340 (-6625 3200);
DISPLAY INVISIBLE (-6625 3200);
FORCEPROP 1 LAST PATH I6
J 0
(-6952 3325);
DISPLAY 0.872340 (-6952 3325);
PAINT GREEN (-6952 3325);
DISPLAY INVISIBLE (-6952 3325);
FORCEADD TAP..1
(-6750 3575);
FORCEPROP 3 LASTPIN (-6800 3575) SIG_NAME P5E_CPU0_P2_TX_C_DP<11>
J 0
(-6790 3585);
DISPLAY 0.659574 (-6790 3585);
PAINT MONO (-6790 3585);
DISPLAY INVISIBLE (-6790 3585);
FORCEPROP 1 LASTPIN (-6800 3575) BN 11
J 0
(-6812 3583);
DISPLAY 0.680851 (-6812 3583);
PAINT GREEN (-6812 3583);
FORCEPROP 2 LAST CDS_LIB standard
J 0
(-6750 3575);
DISPLAY INVISIBLE (-6750 3575);
FORCEPROP 1 LAST BODY_TYPE PLUMBING
J 0
(-6750 3625);
DISPLAY 0.872340 (-6750 3625);
PAINT GREEN (-6750 3625);
DISPLAY INVISIBLE (-6750 3625);
FORCEPROP 1 LAST HDL_TAP TRUE
J 0
(-6425 3450);
DISPLAY 0.872340 (-6425 3450);
DISPLAY INVISIBLE (-6425 3450);
FORCEPROP 1 LAST PATH I7
J 0
(-6752 3575);
DISPLAY 0.872340 (-6752 3575);
PAINT GREEN (-6752 3575);
DISPLAY INVISIBLE (-6752 3575);
FORCEADD TAP..1
(-6950 3675);
FORCEPROP 3 LASTPIN (-7000 3675) SIG_NAME P5E_CPU0_P2_TX_C_DN<11>
J 0
(-6990 3685);
DISPLAY 0.659574 (-6990 3685);
PAINT MONO (-6990 3685);
DISPLAY INVISIBLE (-6990 3685);
FORCEPROP 1 LASTPIN (-7000 3675) BN 11
J 0
(-7012 3683);
DISPLAY 0.680851 (-7012 3683);
PAINT GREEN (-7012 3683);
FORCEPROP 2 LAST CDS_LIB standard
J 0
(-6950 3675);
DISPLAY INVISIBLE (-6950 3675);
FORCEPROP 1 LAST BODY_TYPE PLUMBING
J 0
(-6950 3725);
DISPLAY 0.872340 (-6950 3725);
PAINT GREEN (-6950 3725);
DISPLAY INVISIBLE (-6950 3725);
FORCEPROP 1 LAST HDL_TAP TRUE
J 0
(-6625 3550);
DISPLAY 0.872340 (-6625 3550);
DISPLAY INVISIBLE (-6625 3550);
FORCEPROP 1 LAST PATH I8
J 0
(-6952 3675);
DISPLAY 0.872340 (-6952 3675);
PAINT GREEN (-6952 3675);
DISPLAY INVISIBLE (-6952 3675);
FORCEADD TAP..1
(-6750 3925);
FORCEPROP 3 LASTPIN (-6800 3925) SIG_NAME P5E_CPU0_P2_TX_C_DP<12>
J 0
(-6790 3935);
DISPLAY 0.659574 (-6790 3935);
PAINT MONO (-6790 3935);
DISPLAY INVISIBLE (-6790 3935);
FORCEPROP 1 LASTPIN (-6800 3925) BN 12
J 0
(-6812 3933);
DISPLAY 0.680851 (-6812 3933);
PAINT GREEN (-6812 3933);
FORCEPROP 2 LAST CDS_LIB standard
J 0
(-6750 3925);
DISPLAY INVISIBLE (-6750 3925);
FORCEPROP 1 LAST BODY_TYPE PLUMBING
J 0
(-6750 3975);
DISPLAY 0.872340 (-6750 3975);
PAINT GREEN (-6750 3975);
DISPLAY INVISIBLE (-6750 3975);
FORCEPROP 1 LAST HDL_TAP TRUE
J 0
(-6425 3800);
DISPLAY 0.872340 (-6425 3800);
DISPLAY INVISIBLE (-6425 3800);
FORCEPROP 1 LAST PATH I9
J 0
(-6752 3925);
DISPLAY 0.872340 (-6752 3925);
PAINT GREEN (-6752 3925);
DISPLAY INVISIBLE (-6752 3925);
FORCEADD QUANTA_TITLE_BLOCK_C..1
(0 0);
FORCEPROP 0 LAST CDS_CON_LAST_MODIFIED Thu Sep 14 16:12:52 2023
J 0
(-1885 15);
DISPLAY INVISIBLE (-1885 15);
FORCEPROP 1 LAST CUSTOM_TXT_CDS <CON_LAST_MODIFIED>
J 0
(-1885 15);
DISPLAY 0.978723 (-1885 15);
FORCEPROP 2 LAST CUSTOM_TXT_CDS <XR_PAGE_TITLE>
J 0
(-7890 5250);
DISPLAY 0.638298 (-7890 5250);
PAINT PINK (-7890 5250);
DISPLAY INVISIBLE (-7890 5250);
FORCEPROP 1 LAST CUSTOM_TXT_CDS <NAME_2>
J 0
(-3175 50);
FORCEPROP 1 LAST CUSTOM_TXT_CDS <NAME_1>
J 0
(-3175 175);
FORCEPROP 1 LAST CUSTOM_TXT_CDS <Q_NUMBER>
J 0
(-1403 103);
DISPLAY 1.212766 (-1403 103);
FORCEPROP 1 LAST CUSTOM_TXT_CDS <Q_PROJ>
J 0
(-2382 102);
DISPLAY 1.212766 (-2382 102);
FORCEPROP 1 LAST CUSTOM_TXT_CDS <Q_REV>
J 0
(-184 103);
DISPLAY 1.212766 (-184 103);
FORCEPROP 1 LAST CUSTOM_TXT_CDS <CON_PAGE_NUM> OF <CON_TOTAL_PAGES>
J 0
(-446 18);
DISPLAY 0.978723 (-446 18);
FORCEPROP 1 LAST Q_TITLE RETIMER_CPU0_P2(1)
J 0
(-9366 26);
DISPLAY 2.446809 (-9366 26);
PAINT GREEN (-9366 26);
FORCEPROP 2 LAST CDS_LIB pure_quanta
J 0
(0 0);
DISPLAY INVISIBLE (0 0);
FORCEPROP 1 LAST CDS_LMAN_SYM_OUTLINE -9475,6775,100,-125
J 0
(0 0);
DISPLAY 0.468085 (0 0);
PAINT GREEN (0 0);
DISPLAY INVISIBLE (0 0);
FORCEPROP 2 LAST PAGE_BORDER TRUE
J 0
(-7890 5250);
DISPLAY 0.638298 (-7890 5250);
PAINT PINK (-7890 5250);
DISPLAY INVISIBLE (-7890 5250);
FORCEPROP 2 LAST CDS_XR_PAGE_TITLE CR-295 : @T6G_MB_LIB.T6G(SCH_1):PAGE295
J 0
(-7890 5250);
DISPLAY 0.638298 (-7890 5250);
PAINT PINK (-7890 5250);
DISPLAY INVISIBLE (-7890 5250);
FORCEPROP 1 LAST Q_DEPT BU9
J 1
(-3763 49);
DISPLAY 1.957447 (-3763 49);
PAINT GREEN (-3763 49);
DISPLAY INVISIBLE (-3763 49);
FORCEPROP 1 LAST COMMENT_BODY TRUE
J 0
(12 -13);
DISPLAY 0.978723 (12 -13);
PAINT GREEN (12 -13);
DISPLAY INVISIBLE (12 -13);
WIRE 17 -1 (-6700 2900)(-6700 2550);
WIRE 17 -1 (-6700 3250)(-6700 2900);
WIRE 17 -1 (-6700 3600)(-6700 3250);
WIRE 17 -1 (-6700 3600)(-6700 3950);
WIRE 17 -1 (-6700 4300)(-6700 3950);
WIRE 17 -1 (-6700 4650)(-6700 4300);
WIRE 17 -1 (-6700 5000)(-6700 4650);
WIRE 17 -1 (-6700 5000)(-5800 5000);
FORCEPROP 2 LAST SIG_NAME P5E_CPU0_P2_TX_C_DP<15:8>
J 0
(-6635 5010);
DISPLAY 0.680851 (-6635 5010);
PAINT WHITE (-6635 5010);
WIRE 17 -1 (-6900 3000)(-6900 2650);
WIRE 17 -1 (-6900 3350)(-6900 3000);
WIRE 17 -1 (-6900 3700)(-6900 3350);
WIRE 17 -1 (-6900 3700)(-6900 4050);
WIRE 17 -1 (-6900 4400)(-6900 4050);
WIRE 17 -1 (-6900 4750)(-6900 4400);
WIRE 17 -1 (-6900 5100)(-6900 4750);
WIRE 17 -1 (-6900 5100)(-5800 5100);
FORCEPROP 2 LAST SIG_NAME P5E_CPU0_P2_TX_C_DN<15:8>
J 0
(-6635 5110);
DISPLAY 0.680851 (-6635 5110);
PAINT WHITE (-6635 5110);
WIRE 17 -1 (-2275 3650)(-2275 4000);
WIRE 17 -1 (-2275 3650)(-2275 3300);
WIRE 17 -1 (-2275 4350)(-2275 4000);
WIRE 17 -1 (-2275 4700)(-2275 4350);
WIRE 17 -1 (-2275 3300)(-2275 2850);
WIRE 17 -1 (-2275 2850)(-2275 2600);
WIRE 17 -1 (-2275 5050)(-2275 4700);
WIRE 17 -1 (-2275 5050)(-1175 5050);
FORCEPROP 2 LAST SIG_NAME P5E_CPU0_P2_TX_C_DN<7:0>
J 0
(-2010 5060);
DISPLAY 0.680851 (-2010 5060);
PAINT WHITE (-2010 5060);
WIRE 17 -1 (-2075 3550)(-2075 3900);
WIRE 17 -1 (-2075 3550)(-2075 3200);
WIRE 17 -1 (-2075 4250)(-2075 3900);
WIRE 17 -1 (-2075 4600)(-2075 4250);
WIRE 17 -1 (-2075 3200)(-2075 2950);
WIRE 17 -1 (-2075 2950)(-2075 2500);
WIRE 17 -1 (-2075 4950)(-2075 4600);
WIRE 17 -1 (-2075 4950)(-1175 4950);
FORCEPROP 2 LAST SIG_NAME P5E_CPU0_P2_TX_C_DP<7:0>
J 0
(-2010 4960);
DISPLAY 0.680851 (-2010 4960);
PAINT WHITE (-2010 4960);
WIRE 16 -1 (-7525 4025)(-7000 4025);
WIRE 16 -1 (-7525 3575)(-6800 3575);
WIRE 16 -1 (-7525 3325)(-7000 3325);
WIRE 16 -1 (-7525 2875)(-6800 2875);
WIRE 16 -1 (-7525 2975)(-7000 2975);
WIRE 16 -1 (-7525 3225)(-6800 3225);
WIRE 16 -1 (-7525 3675)(-7000 3675);
WIRE 16 -1 (-7525 3925)(-6800 3925);
WIRE 16 -1 (-7525 4275)(-6800 4275);
WIRE 16 -1 (-7525 4625)(-6800 4625);
WIRE 16 -1 (-7525 4725)(-7000 4725);
WIRE 16 -1 (-7525 4975)(-6800 4975);
WIRE 16 -1 (-2900 4575)(-2175 4575);
WIRE 16 -1 (-2900 4675)(-2375 4675);
WIRE 16 -1 (-2900 3275)(-2375 3275);
WIRE 16 -1 (-2900 3175)(-2175 3175);
WIRE 16 -1 (-7525 5075)(-7000 5075);
WIRE 16 -1 (-2900 4325)(-2375 4325);
WIRE 16 -1 (-2900 4925)(-2175 4925);
WIRE 16 -1 (-2900 4225)(-2175 4225);
WIRE 16 -1 (-2900 3875)(-2175 3875);
WIRE 16 -1 (-2375 2825)(-2900 2825);
WIRE 16 -1 (-2175 2925)(-2900 2925);
WIRE 16 -1 (-2900 2575)(-2375 2575);
WIRE 16 -1 (-2900 2475)(-2175 2475);
WIRE 16 -1 (-7525 4375)(-7000 4375);
WIRE 16 -1 (-2900 3625)(-2375 3625);
WIRE 16 -1 (-2900 3525)(-2175 3525);
WIRE 16 -1 (-2900 5025)(-2375 5025);
WIRE 16 -1 (-2900 3975)(-2375 3975);
WIRE 16 -1 (-7525 2625)(-7000 2625);
WIRE 16 -1 (-7525 2525)(-6800 2525);
FORCENOTE
P5E_CPU0_P2_TX_C_DP/DN<0-15> LANE REVERSAL
(-9050 6300) 0;
DISPLAY LEFT (-9050 6300);
DISPLAY 2.000000 (-9050 6300);
FORCENOTE
CPU TO RETIMER
(-3800 1675) 0;
DISPLAY LEFT (-3800 1675);
DISPLAY 3.148936 (-3800 1675);
FORCENOTE
CPU TO RETIMER
(-8400 1675) 0;
DISPLAY LEFT (-8400 1675);
DISPLAY 3.148936 (-8400 1675);
FORCENOTE
P/N SWAP
(-1950 3200) 0;
DISPLAY LEFT (-1950 3200);
DISPLAY 1.021277 (-1950 3200);
FORCENOTE
P/N SWAP
(-1950 3600) 0;
DISPLAY LEFT (-1950 3600);
DISPLAY 1.021277 (-1950 3600);
FORCENOTE
P/N SWAP
(-1900 3950) 0;
DISPLAY LEFT (-1900 3950);
DISPLAY 1.021277 (-1900 3950);
FORCENOTE
P/N SWAP
(-1875 4250) 0;
DISPLAY LEFT (-1875 4250);
DISPLAY 1.021277 (-1875 4250);
FORCENOTE
P/N SWAP
(-1900 4575) 0;
DISPLAY LEFT (-1900 4575);
DISPLAY 1.021277 (-1900 4575);
FORCENOTE
P/N SWAP
(-1900 4825) 0;
DISPLAY LEFT (-1900 4825);
DISPLAY 1.021277 (-1900 4825);
FORCENOTE
P/N SWAP
(-6625 2525) 0;
DISPLAY LEFT (-6625 2525);
DISPLAY 1.021277 (-6625 2525);
FORCENOTE
P/N SWAP
(-6600 2900) 0;
DISPLAY LEFT (-6600 2900);
DISPLAY 1.021277 (-6600 2900);
FORCENOTE
P/N SWAP
(-6600 3275) 0;
DISPLAY LEFT (-6600 3275);
DISPLAY 1.021277 (-6600 3275);
FORCENOTE
P/N SWAP
(-6575 3600) 0;
DISPLAY LEFT (-6575 3600);
DISPLAY 1.021277 (-6575 3600);
FORCENOTE
P/N SWAP
(-6550 3950) 0;
DISPLAY LEFT (-6550 3950);
DISPLAY 1.021277 (-6550 3950);
FORCENOTE
P/N SWAP
(-6575 4300) 0;
DISPLAY LEFT (-6575 4300);
DISPLAY 1.021277 (-6575 4300);
FORCENOTE
P/N SWAP
(-6600 4625) 0;
DISPLAY LEFT (-6600 4625);
DISPLAY 1.021277 (-6600 4625);
FORCENOTE
P/N SWAP
(-6600 4925) 0;
DISPLAY LEFT (-6600 4925);
DISPLAY 1.021277 (-6600 4925);
FORCENOTE
P/N SWAP
(-1925 2525) 0;
DISPLAY LEFT (-1925 2525);
DISPLAY 1.021277 (-1925 2525);
QUIT
